FILE_TYPE = CONNECTIVITY;
{Allegro Design Entry HDL 16.6-p007 (v16-6-112F) 10/10/2012}
"PAGE_NUMBER" = 211;
0"NC";
1"GND\g";
2"GND\g";
3"PVCCIO_CPU0\g";
4"GND\g";
5"GND\g";
6"GND\g";
7"P3V3_STBY\g";
8"PVCCIO_CPU0\g";
9"VR_FET_SW_P12V_STBY_PVCCIO_CPU0\g";
10"GND\g";
11"GND\g";
12"GND\g";
13"GND\g";
14"P3V3_STBY\g";
15"GND\g";
16"SVID_DIO0_CPU0_R";
17"VR_PVCCIO_CPU0_VDD";
18"IRQ_PVCCIO_CPU0_VRHOT_N";
19"VR_PVCCIO_CPU0_VD12";
20"VR_PVCCIO_CPU0_PWM1"VOLTAGE"3.3";
21"PWRGD_PVCCIO_CPU0";
22"SVID_ALERT0_CPU0_R_N";
23"PWRGD_PVCCIO_CPU0_R";
24"PU_VR_PVCCIO_CPU0_FAULT1";
25"TP_VR_PVCCIO_CPU0_MP1";
26"TP_VR_PVCCIO_CPU0_MP3";
27"TP_VR_PVCCIO_CPU0_MP0";
28"TP_VR_PVCCIO_CPU0_MP2";
29"NC_PVCCIO_CPU0_DNC4";
30"NC_PVCCIO_CPU0_DNC3";
31"NC_PVCCIO_CPU0_DNC2";
32"NC_PVCCIO_CPU0_DNC1";
33"NC_PVCCIO_CPU0_DNC0";
34"TP_PVCCIO_CPU0_BPWM1";
35"TP_PVCCIO_CPU0_PINALRT_N";
36"SVID_ALERT_PVCCIO_CPU0";
37"VR_PVCCIO_CPU0_VINSEN"VOLTAGE"0.8";
38"VR_PVCCIO_CPU0_EN";
39"SVID_CLK0_CPU0_R";
40"SVID_CLK_PVCCIO_CPU0";
41"VR_PVCCIO_CPU0_XADDR1"VOLTAGE"3.3";
42"VR_PVCCIO_CPU0_XADDR2"VOLTAGE"3.3V";
43"TP_PVCCIO_CPU0_RESET_N";
44"SMB_VR_SDA_PVCCIO_CPU0";
45"SMB_VR_SCL_PVCCIO_CPU0";
46"SVID_VDIO_PVCCIO_CPU0";
47"TP_PVCCIO_CPU0_BTSEN";
48"TP_PVCCIO_CPU0_BIREF1";
49"TP_PVCCIO_CPU0_BVSEN";
50"TP_PVCCIO_CPU0_BVREF";
51"TP_VR_PVCCIO_CPU0_AIINSEN";
52"VSENSE_PVCCIO_CPU0_AVSN";
53"VR_PVCCIO_CPU0_AVSP"VOLTAGE"2";
54"VR_PVCCIO_CPU0_AIREF1";
55"VR_PVCCIO_CPU0_VD12";
56"VR_PVCCIO_CPU0_VINSEN";
57"ISENSE_PVCCIO_CPU0_PH1_IMON";
58"A_TSENSE_PVCCIO_CPU0"VOLTAGE"3.6";
59"SMB_VR_STBY_LVC3_SCL";
60"SMB_VR_STBY_LVC3_SDA";
61"FM_PVCCIO_CPU0_EN";
62"VSENSE_PVCCIO_CPU0_AVSP";
63"VR_PVCCIO_CPU0_VD12";
%"CAP_A"
"1","(2475,1425)","0","dev_discrete","I11";
;
ROOM"PVCCIO_CPU0"
SEC"1"
SEC_TYPE"0402V"
CDS_SEC"1"
CDS_LOCATION"C3P4"
CDS_LIB"dev_discrete"
LOCATION"C3P4"
PART_NUMBER"D97712-004"
VALUE"1.0UF"
TOLERANCE"10%"
PACK_TYPE"0402V"
VOLTAGE"6.3V"
MATERIAL"X6S";
"B"
$PN"2"1;
"A"
$PN"1"19;
%"GND"
"1","(2475,1100)","0","mstr_symbols","I12";
;
HDL_POWER"GND"
BODY_TYPE"PLUMBING"
VOLTAGE"0"
SIZE"1B"
CDS_LIB"mstr_symbols"
ROOM"PVCCIO_CPU0";
"A\NAC"1;
%"CAP_A"
"1","(2075,1425)","0","dev_discrete","I13";
;
SEC"1"
SEC_TYPE"0402V"
CDS_SEC"1"
ROOM"PVCCIO_CPU0"
CDS_LOCATION"C3P5"
CDS_LIB"dev_discrete"
LOCATION"C3P5"
PART_NUMBER"A36096-030"
VALUE"0.1UF"
TOLERANCE"10%"
VOLTAGE"16V"
MATERIAL"X7R"
PACK_TYPE"0402V";
"B"
$PN"2"2;
"A"
$PN"1"19;
%"GND"
"1","(2075,1225)","0","mstr_symbols","I14";
;
HDL_POWER"GND"
BODY_TYPE"PLUMBING"
CDS_LIB"mstr_symbols"
SIZE"1B"
VOLTAGE"0"
ROOM"PVCCIO_CPU0";
"A\NAC"2;
%"RES"
"1","(-1250,2950)","0","mstr_discrete","I16";
;
CDS_SEC"1"
SEC_TYPE"0402"
SEC"1"
ROOM"PVCCIO_CPU0"
CDS_LIB"mstr_discrete"
CDS_LOCATION"R3P11"
PACK_TYPE"0402"
MATERIAL"CHIP"
LOCATION"R3P11"
PART_NUMBER"G21497-005"
TOLERANCE"5%"
WATTAGE"1/16W"
VALUE"0.0";
"B"
$PN"2"46;
"A"
$PN"1"16;
%"RES"
"2","(-1675,4500)","0","mstr_discrete","I17";
;
CDS_SEC"1"
SEC_TYPE"0402"
SEC"1"
CDS_LOCATION"R3P13"
ROOM"PVCCIO_CPU0"
CDS_LIB"mstr_discrete"
MATERIAL"EMPTY"
LOCATION"R3P13"
PART_NUMBER"G21796-017"
VALUE"100.0"
PACK_TYPE"0402"
WATTAGE"1/16W"
TOLERANCE"1%";
"A"
$PN"1"3;
"B"
$PN"2"16;
%"PVCCIO_CPU0"
"1","(-1675,4825)","0","mstr_symbols","I18";
;
HDL_POWER"PVCCIO_CPU0"
BODY_TYPE"PLUMBING"
VOLTAGE"1.1V"
CDS_LIB"mstr_symbols";
"G\NAC"3;
%"GND"
"1","(925,1900)","0","mstr_symbols","I2";
;
HDL_POWER"GND"
BODY_TYPE"PLUMBING"
ROOM"PVCCIO_CPU0"
CDS_LIB"mstr_symbols"
SIZE"1B"
VOLTAGE"0";
"A\NAC"4;
%"CAP_A"
"1","(75,4175)","0","dev_discrete","I20";
;
$SEC"1"
CDS_SEC"1"
ROOM"PVCCIO_CPU0"
CDS_LOCATION"C3P3"
CDS_LIB"dev_discrete"
VALUE"1.0UF"
LOCATION"C3P3"
TOLERANCE"10%"
VOLTAGE"6.3V"
MATERIAL"X6S"
PART_NUMBER"D97712-004"
PACK_TYPE"0402V";
"B"
$PN"2"5;
"A"
$PN"1"17;
%"GND"
"1","(75,3975)","0","mstr_symbols","I21";
;
HDL_POWER"GND"
BODY_TYPE"PLUMBING"
SIZE"1B"
VOLTAGE"0"
CDS_LIB"mstr_symbols"
ROOM"PVCCIO_CPU0";
"A\NAC"5;
%"CAP_A"
"1","(-325,4175)","0","dev_discrete","I22";
;
SEC_TYPE"0402V"
SEC"1"
CDS_SEC"1"
ROOM"PVCCIO_CPU0"
CDS_LOCATION"C3P7"
CDS_LIB"dev_discrete"
PART_NUMBER"A36096-030"
LOCATION"C3P7"
VALUE"0.1UF"
TOLERANCE"10%"
VOLTAGE"16V"
MATERIAL"X7R"
PACK_TYPE"0402V";
"B"
$PN"2"6;
"A"
$PN"1"17;
%"GND"
"1","(-325,3975)","0","mstr_symbols","I23";
;
HDL_POWER"GND"
BODY_TYPE"PLUMBING"
ROOM"PVCCIO_CPU0"
SIZE"1B"
VOLTAGE"0"
CDS_LIB"mstr_symbols";
"A\NAC"6;
%"RES"
"2","(-625,4525)","0","mstr_discrete","I24";
;
CDS_SEC"1"
SEC_TYPE"0402"
ROOM"PVCCIO_CPU0"
SEC"1"
CDS_LOCATION"R3P22"
CDS_LIB"mstr_discrete"
LOCATION"R3P22"
PART_NUMBER"G21497-005"
VALUE"0.0"
PACK_TYPE"0402"
MATERIAL"CHIP"
WATTAGE"1/16W"
TOLERANCE"5%";
"A"
$PN"1"7;
"B"
$PN"2"17;
%"P3V3_STBY"
"1","(-625,4850)","0","mstr_symbols","I25";
;
HDL_POWER"P3V3_STBY"
BODY_TYPE"PLUMBING"
SIZE"1B"
CDS_LIB"mstr_symbols"
VOLTAGE"3.3V";
"G\NAC"7;
%"PVCCIO_CPU0"
"1","(-2125,4875)","0","mstr_symbols","I27";
;
HDL_POWER"PVCCIO_CPU0"
BODY_TYPE"PLUMBING"
CDS_LIB"mstr_symbols"
VOLTAGE"1.1V";
"G\NAC"8;
%"RES"
"2","(-2125,4525)","0","mstr_discrete","I28";
;
CDS_SEC"1"
SEC"1"
SEC_TYPE"0402"
ROOM"PVCCIO_CPU0"
CDS_LOCATION"R3P17"
CDS_LIB"mstr_discrete"
MATERIAL"EMPTY"
LOCATION"R3P17"
PART_NUMBER"G21796-047"
VALUE"49.9"
TOLERANCE"1%"
PACK_TYPE"0402"
WATTAGE"1/16W";
"A"
$PN"1"8;
"B"
$PN"2"39;
%"RES"
"1","(-1975,3975)","0","mstr_discrete","I29";
;
CDS_SEC"1"
SEC_TYPE"0402"
SEC"1"
CDS_LOCATION"R3P15"
ROOM"PVCCIO_CPU0"
CDS_LIB"mstr_discrete"
LOCATION"R3P15"
PART_NUMBER"G21796-009"
MATERIAL"CHIP"
PACK_TYPE"0402"
TOLERANCE"1%"
VALUE"150.0"
WATTAGE"1/16W";
"B"
$PN"2"40;
"A"
$PN"1"39;
%"VCC_CORE"
"1","(-2500,4850)","0","mstr_symbols","I30";
;
CDS_LIB"mstr_symbols"
HDL_POWER"VR_FET_SW_P12V_STBY_PVCCIO_CPU0";
"A"9;
%"RES"
"2","(-2500,4650)","0","mstr_discrete","I31";
;
CDS_SEC"1"
SEC_TYPE"0402"
SEC"1"
NO_XNET_CONNECTION"1"
ROOM"PVCCIO_CPU0"
CDS_LIB"mstr_discrete"
CDS_LOCATION"R3P12"
VALUE"100.0K"
WATTAGE"1/16W"
TOLERANCE"1%"
PART_NUMBER"G21796-160"
MATERIAL"CHIP"
PACK_TYPE"0402"
LOCATION"R3P12";
"A"
$PN"1"9;
"B"
$PN"2"37;
%"RES"
"2","(-2500,4300)","0","mstr_discrete","I32";
;
CDS_SEC"1"
SEC_TYPE"0402"
SEC"1"
ROOM"PVCCIO_CPU0"
CDS_LIB"mstr_discrete"
CDS_LOCATION"R3P16"
PART_NUMBER"G21796-003"
VALUE"1.5K"
TOLERANCE"1%"
PACK_TYPE"0402"
MATERIAL"CHIP"
WATTAGE"1/16W"
LOCATION"R3P16";
"A"
$PN"1"37;
"B"
$PN"2"10;
%"CAP"
"1","(-2725,4275)","2","mstr_discrete","I33";
;
CDS_SEC"1"
CDS_LOCATION"C3P2"
ROOM"PVCCIO_CPU0"
SEC_TYPE"0402LF"
SEC"1"
CDS_LIB"mstr_discrete"
LOCATION"C3P2"
PART_NUMBER"A36096-046"
VALUE"1000PF"
TOLERANCE"10%"
VOLTAGE"50V"
MATERIAL"X7R"
PACK_TYPE"0402LF";
"A"
$PN"1"37;
"B"
$PN"2"11;
%"GND"
"1","(-2500,4100)","0","mstr_symbols","I34";
;
HDL_POWER"GND"
BODY_TYPE"PLUMBING"
VOLTAGE"0"
CDS_LIB"mstr_symbols"
ROOM"PVCCIO_CPU0"
SIZE"1B";
"A\NAC"10;
%"GND"
"1","(-2725,4075)","0","mstr_symbols","I35";
;
HDL_POWER"GND"
BODY_TYPE"PLUMBING"
ROOM"PVCCIO_CPU0"
VOLTAGE"0"
CDS_LIB"mstr_symbols"
SIZE"1B";
"A\NAC"11;
%"RES"
"1","(-1575,2400)","0","mstr_discrete","I46";
;
CDS_SEC"1"
$SEC"1"
CDS_LOCATION"R3P24"
CDS_LIB"mstr_discrete"
ROOM"PVCCIO_CPU0"
LOCATION"R3P24"
PART_NUMBER"G21796-173"
TOLERANCE"1%"
PACK_TYPE"0402"
MATERIAL"CHIP"
VALUE"20.0"
WATTAGE"1/16W";
"B"
$PN"2"45;
"A"
$PN"1"59;
%"RES"
"1","(-1250,2450)","0","mstr_discrete","I47";
;
CDS_SEC"1"
$SEC"1"
ROOM"PVCCIO_CPU0"
CDS_LIB"mstr_discrete"
CDS_LOCATION"R3P23"
PART_NUMBER"G21796-173"
TOLERANCE"1%"
MATERIAL"CHIP"
PACK_TYPE"0402"
LOCATION"R3P23"
VALUE"20.0"
WATTAGE"1/16W";
"B"
$PN"2"44;
"A"
$PN"1"60;
%"GND"
"1","(-1025,2050)","0","mstr_symbols","I51";
;
HDL_POWER"GND"
BODY_TYPE"PLUMBING"
CDS_LIB"mstr_symbols"
VOLTAGE"0"
ROOM"PVCCIO_CPU0"
SIZE"1B";
"A\NAC"12;
%"RES"
"2","(-925,1350)","0","mstr_discrete","I52";
;
CDS_LOCATION"R3N31"
CDS_SEC"1"
$SEC"1"
ROOM"PVCCIO_CPU0"
CDS_LIB"mstr_discrete"
LOCATION"R3N31"
PART_NUMBER"G21796-043"
VALUE"3.16K"
WATTAGE"1/16W"
TOLERANCE"1%"
MATERIAL"CHIP"
PACK_TYPE"0402";
"A"
$PN"1"41;
"B"
$PN"2"13;
%"GND"
"1","(-925,775)","0","mstr_symbols","I54";
;
HDL_POWER"GND"
BODY_TYPE"PLUMBING"
CDS_LIB"mstr_symbols"
SIZE"1B"
VOLTAGE"0"
ROOM"PVCCIO_CPU0";
"A\NAC"13;
%"RES"
"2","(775,4100)","0","mstr_discrete","I56";
;
CDS_SEC"1"
SEC_TYPE"0402"
SEC"1"
ROOM"PVCCIO_CPU0"
CDS_LIB"mstr_discrete"
CDS_LOCATION"R3P25"
TOLERANCE"1%"
VALUE"1.00K"
LOCATION"R3P25"
WATTAGE"1/16W"
PART_NUMBER"G21796-026"
MATERIAL"CHIP"
PACK_TYPE"0402";
"A"
$PN"1"14;
"B"
$PN"2"23;
%"RES"
"1","(1875,3600)","0","mstr_discrete","I58";
;
CDS_SEC"1"
SEC_TYPE"0402"
ROOM"PVCCIO_CPU0"
CDS_LIB"mstr_discrete"
SEC"1"
CDS_LOCATION"R3P20"
PACK_TYPE"0402"
PART_NUMBER"G21796-250"
LOCATION"R3P20"
VALUE"22.1"
TOLERANCE"1.0%"
MATERIAL"CHIP"
WATTAGE"1/16W";
"B"
$PN"2"21;
"A"
$PN"1"23;
%"P3V3_STBY"
"1","(1800,4775)","0","mstr_symbols","I59";
;
HDL_POWER"P3V3_STBY"
BODY_TYPE"PLUMBING"
VOLTAGE"3.3V"
CDS_LIB"mstr_symbols"
SIZE"1B";
"G\NAC"14;
%"RES"
"2","(1525,4100)","0","mstr_discrete","I60";
;
CDS_SEC"1"
SEC"1"
CDS_LOCATION"R3N23"
SEC_TYPE"0402"
CDS_LIB"mstr_discrete"
ROOM"PVCCIO_CPU0"
TOLERANCE"1.0%"
VALUE"2.26K"
LOCATION"R3N23"
WATTAGE"1/16W"
PART_NUMBER"G21796-311"
PACK_TYPE"0402"
MATERIAL"EMPTY";
"A"
$PN"1"14;
"B"
$PN"2"24;
%"RES"
"1","(1300,3150)","0","mstr_discrete","I61";
;
CDS_SEC"1"
CDS_LIB"mstr_discrete"
ROOM"PVCCIO_CPU0"
SEC"1"
CDS_LOCATION"R3P1"
SEC_TYPE"0402"
MATERIAL"CHIP"
PACK_TYPE"0402"
TOLERANCE"5%"
LOCATION"R3P1"
WATTAGE"1/16W"
VALUE"0.0"
PART_NUMBER"G21497-005";
"B"
$PN"2"22;
"A"
$PN"1"36;
%"RES"
"2","(2075,4050)","0","mstr_discrete","I64";
;
CDS_SEC"1"
SEC_TYPE"0402"
SEC"1"
CDS_LOCATION"R3P18"
CDS_LIB"mstr_discrete"
VALUE"1.00K"
LOCATION"R3P18"
TOLERANCE"1%"
PART_NUMBER"G21796-026"
WATTAGE"1/16W"
MATERIAL"CHIP"
PACK_TYPE"0402";
"A"
$PN"1"14;
"B"
$PN"2"18;
%"RES"
"2","(-575,1375)","0","mstr_discrete","I65";
;
CDS_SEC"1"
$SEC"1"
CDS_LOCATION"R3N22"
CDS_LIB"mstr_discrete"
LOCATION"R3N22"
PART_NUMBER"G21796-082"
VALUE"4.02K"
TOLERANCE"1%"
PACK_TYPE"0402"
MATERIAL"CHIP"
WATTAGE"1/16W";
"A"
$PN"1"42;
"B"
$PN"2"13;
%"CAP"
"1","(1650,2750)","0","mstr_discrete","I71";
;
CDS_SEC"1"
ROOM"PVCCIO_CPU0_VR"
SEC"1"
SEC_TYPE"0402LF"
CDS_LOCATION"C3P6"
CDS_LIB"mstr_discrete"
VALUE"1000PF"
PART_NUMBER"A36096-046"
LOCATION"C3P6"
VOLTAGE"50V"
TOLERANCE"10%"
MATERIAL"X7R"
PACK_TYPE"0402LF";
"A"
$PN"1"23;
"B"
$PN"2"15;
%"GND"
"1","(1650,2475)","0","mstr_symbols","I72";
;
HDL_POWER"GND"
BODY_TYPE"PLUMBING"
VOLTAGE"0"
CDS_LIB"mstr_symbols"
SIZE"1B"
ROOM"PVCCIO_CPU0";
"A\NAC"15;
%"RES"
"1","(-2600,2050)","0","mstr_discrete","I81";
;
ROOM"PVCCIO_CPU0"
CDS_LIB"mstr_discrete"
CDS_SEC"1"
$SEC"1"
CDS_LOCATION"R3N19"
LOCATION"R3N19"
PART_NUMBER"G21796-066"
PACK_TYPE"0402"
MATERIAL"CHIP"
VALUE"10.0"
TOLERANCE"1%"
WATTAGE"1/16W";
"B"
$PN"2"53;
"A"
$PN"1"62;
%"CAP"
"1","(-2400,1850)","0","mstr_discrete","I83";
;
CDS_SEC"1"
SEC"1"
SEC_TYPE"0402LF"
ROOM"PVCCIO_CPU0"
CDS_LOCATION"C3N39"
CDS_LIB"mstr_discrete"
MATERIAL"X7R"
TOLERANCE"10%"
VALUE"220PF"
PART_NUMBER"A36096-050"
PACK_TYPE"0402LF"
VOLTAGE"50V"
LOCATION"C3N39";
"A"
$PN"1"53;
"B"
$PN"2"52;
%"RES"
"1","(-1950,3250)","0","mstr_discrete","I87";
;
$SEC"1"
CDS_SEC"1"
ROOM"PVCCIN_CPU0_VR"
CDS_LOCATION"R3P26"
CDS_LIB"mstr_discrete"
PACK_TYPE"0402"
MATERIAL"CHIP"
LOCATION"R3P26"
TOLERANCE"5%"
PART_NUMBER"G21497-005"
WATTAGE"1/16W"
VALUE"0.0";
"B"
$PN"2"38;
"A"
$PN"1"61;
%"RES"
"2","(-1125,4300)","0","mstr_discrete","I88";
;
BOM_COST"SM_CONTROLLER"
CDS_SEC"1"
$SEC"1"
CDS_LOCATION"R3P21"
ROOM"BMC"
CDS_LIB"mstr_discrete"
MATERIAL"EMPTY"
LOCATION"R3P21"
PART_NUMBER"G21796-010"
VALUE"100.0K"
TOLERANCE"1%"
PACK_TYPE"0402"
WATTAGE"1/16W";
"A"
$PN"1"7;
"B"
$PN"2"38;
%"RES"
"1","(-2450,3750)","0","mstr_discrete","I91";
;
CDS_LOCATION"R3P57"
ROOM"PVCCIN_CPU0_VR"
$SEC"1"
CDS_SEC"1"
CDS_LIB"mstr_discrete"
PACK_TYPE"0402"
MATERIAL"CHIP"
LOCATION"R3P57"
TOLERANCE"5%"
PART_NUMBER"G21497-005"
VALUE"0.0"
WATTAGE"1/16W";
"B"
$PN"2"54;
"A"
$PN"1"63;
%"PXE1110B"
"1","(100,2850)","0","mstr_controller","I93";
;
CDS_SEC"1"
CDS_LMAN_SYM_OUTLINE"-400,850,400,-850"
CDS_LIB"mstr_controller"
PACK_TYPE"QFN"
SEC_TYPE"QFN"
SEC"1"
CDS_LOCATION"EU3P1"
MATERIAL"IC"
LOCATION"EU3P1"
PART_NUMBER"H89187-001";
"AVREN"
$PN"10"38;
"AVRRDY"
$PN"9"23;
"MP4"
$PN"32"24;
"MP3"
$PN"31"26;
"MP2"
$PN"18"28;
"MP1"
$PN"14"25;
"MP0"
$PN"13"27;
"DNC<3>"
$PN"24"30;
"VD12"
$PN"40"55;
"IINSEN"
$PN"38"51;
"VINSEN"
$PN"37"56;
"BVREF"
$PN"30"50;
"BVSEN"
$PN"29"49;
"AVREF"
$PN"20"52;
"AVSEN"
$PN"19"53;
"VALRT_N \B"
$PN"17"36;
"PINALRT_N \B"
$PN"12"35;
"VRHOT_N \B"
$PN"11"18;
"GND<1>"
$PN"23"4;
"GND<0>"
$PN"27"4;
"DNC<4>"
$PN"28"29;
"DNC<2>"
$PN"4"31;
"DNC<1>"
$PN"2"32;
"DNC<0>"
$PN"1"33;
"BIREF1"
$PN"25"48;
"BISEN1"
$PN"26"12;
"BTSEN"
$PN"34"47;
"VDD"
$PN"39"17;
"AIREF1"
$PN"21"54;
"AISEN1"
$PN"22"57;
"ATSEN"
$PN"35"58;
"XADDR2"
$PN"33"42;
"XADDR1"
$PN"36"41;
"RESET_N \B"
$PN"8"43;
"VDIO"
$PN"16"46;
"VCLK"
$PN"15"40;
"SCL"
$PN"7"45;
"SDA"
$PN"6"44;
"APWM1"
$PN"5"20;
"BPWM1"
$PN"3"34;
"THPAD"
$PN"41"4;
END.
